# BASEBOARD_FAB2 (Tioga Pass) — schematic netlist excerpt (pin names and nets, part order shuffled) for the footprints in the layout excerpt that follows; sources: Cadence DE-HDL packaged netlist, KiCad conversion of Wiwynn_Tioga_Pass_MB.brd

L1C2  IND-120NH-30-GP  pkg DISCRET-GB2  page 209 : S = VR_PVCCIN_CPU1_PHASE5 ; F = PVCCIN_CPU1
C2F2  CAP_A  47UF 4V 20% X5R  pkg 0603V  page 229 : A = PVTT_GHJ ; B = GND
R7D30  RES  4.75K 1% CHIP  pkg 0402  page 135 : A = P3V3_STBY ; B = FM_CPLD_UART_CH_LOCK_N

(kicad_pcb
	(version 20260206)
	(generator "pcbnew")
	(generator_version "10.0")
	(general
		(thickness 1.6)
		(legacy_teardrops no)
	)
	(paper "A4")
	(title_block
		(title "Wiwynn_Tioga_Pass_MB.brd")
		(comment 1 "Tioga Pass / footprints 1813-1815 of 4770")
	)
	(layers
		(0 "F.Cu" signal "TOP")
		(4 "In1.Cu" signal "L2GND")
		(6 "In2.Cu" signal "L3")
		(8 "In3.Cu" signal "L4GND")
		(10 "In4.Cu" signal "L5")
		(12 "In5.Cu" signal "L6GND")
		(14 "In6.Cu" signal "L7VCC")
		(16 "In7.Cu" signal "L8VCC")
		(18 "In8.Cu" signal "L9GND")
		(20 "In9.Cu" signal "L10")
		(22 "In10.Cu" signal "L11GND")
		(24 "In11.Cu" signal "L12")
		(26 "In12.Cu" signal "L13GND")
		(2 "B.Cu" signal "BOTTOM")
		(9 "F.Adhes" user "F.Adhesive")
		(11 "B.Adhes" user "B.Adhesive")
		(13 "F.Paste" user "Package Geometry/Pastemask Top")
		(15 "B.Paste" user "Package Geometry/Pastemask Bottom")
		(5 "F.SilkS" user "Ref Des/Silkscreen Top")
		(7 "B.SilkS" user "Ref Des/Silkscreen Bottom")
		(1 "F.Mask" user "Board Geometry/Soldermask Top")
		(3 "B.Mask" user "Board Geometry/Soldermask Bottom")
		(17 "Dwgs.User" user "User.Drawings")
		(19 "Cmts.User" user "User.Comments")
		(21 "Eco1.User" user "User.Eco1")
		(23 "Eco2.User" user "User.Eco2")
		(25 "Edge.Cuts" user "Board Geometry/Outline")
		(27 "Margin" user)
		(31 "F.CrtYd" user "Package Geometry/Place Bound Top")
		(29 "B.CrtYd" user "Package Geometry/Place Bound Bottom")
		(35 "F.Fab" user "Ref Des/Assembly Top")
		(33 "B.Fab" user "Ref Des/Assembly Bottom")
	)
	(footprint ""
		(layer "F.Cu")
		(at 96.746568 -23.241 180)
		(property "Reference" "C2F2"
			(at 0 0 180)
			(layer "F.SilkS")
			(hide yes)
			(effects
				(font
					(size 1.27 1.27)
				)
			)
		)
		(property "Value" ""
			(at 0 0 180)
			(layer "F.Fab")
			(effects
				(font
					(size 1.27 1.27)
				)
			)
		)
		(duplicate_pad_numbers_are_jumpers no)
		(fp_rect
			(start -0.500126 1.598422)
			(end 0.500126 -0.201422)
			(stroke
				(width 0)
				(type default)
			)
			(fill no)
			(layer "F.CrtYd")
		)
		(fp_line
			(start 0.500126 1.598422)
			(end -0.500126 1.598422)
			(stroke
				(width 0.1)
				(type default)
			)
			(layer "F.Fab")
		)
		(fp_line
			(start 0.500126 -0.201422)
			(end 0.500126 1.598422)
			(stroke
				(width 0.1)
				(type default)
			)
			(layer "F.Fab")
		)
		(fp_line
			(start -0.500126 1.598422)
			(end -0.500126 -0.201422)
			(stroke
				(width 0.1)
				(type default)
			)
			(layer "F.Fab")
		)
		(fp_line
			(start -0.500126 -0.201422)
			(end 0.500126 -0.201422)
			(stroke
				(width 0.1)
				(type default)
			)
			(layer "F.Fab")
		)
		(pad "1" smd rect
			(at 0 0 90)
			(size 0.889 0.9906)
			(layers "F.Cu" "F.Mask" "F.Paste")
			(net "PVTT_GHJ")
		)
		(pad "2" smd rect
			(at 0 1.397 90)
			(size 0.889 0.9906)
			(layers "F.Cu" "F.Mask" "F.Paste")
			(net "GND")
		)
		(zone
			(layer "F.Cu")
			(hatch none 0.5)
			(connect_pads
				(clearance 0)
			)
			(min_thickness 0.25)
			(keepout
				(tracks not_allowed)
				(vias allowed)
				(pads allowed)
				(copperpour not_allowed)
				(footprints allowed)
			)
			(placement
				(enabled no)
				(sheetname "")
			)
			(fill
				(thermal_gap 0.5)
				(thermal_bridge_width 0.5)
				(island_removal_mode 0)
			)
			(polygon
				(pts
					(xy 97.241868 -24.1935) (xy 96.251268 -24.1935) (xy 96.251268 -23.6855) (xy 97.241868 -23.6855)
				)
			)
		)
		(zone
			(layer "F.Cu")
			(hatch none 0.5)
			(connect_pads
				(clearance 0)
			)
			(min_thickness 0.25)
			(keepout
				(tracks allowed)
				(vias not_allowed)
				(pads allowed)
				(copperpour not_allowed)
				(footprints allowed)
			)
			(placement
				(enabled no)
				(sheetname "")
			)
			(fill
				(thermal_gap 0.5)
				(thermal_bridge_width 0.5)
				(island_removal_mode 0)
			)
			(polygon
				(pts
					(xy 97.241868 -24.1935) (xy 96.251268 -24.1935) (xy 96.251268 -23.6855) (xy 97.241868 -23.6855)
				)
			)
		)
	)
	(footprint ""
		(layer "F.Cu")
		(at 445.1985 -1.143 90)
		(property "Reference" "R7D30"
			(at 0 0 90)
			(layer "F.SilkS")
			(hide yes)
			(effects
				(font
					(size 1.27 1.27)
				)
			)
		)
		(property "Value" ""
			(at 0 0 90)
			(layer "F.Fab")
			(effects
				(font
					(size 1.27 1.27)
				)
			)
		)
		(duplicate_pad_numbers_are_jumpers no)
		(fp_poly
			(pts
				(xy -0.2794 -0.1016) (xy 0.2794 -0.1016) (xy 0.2794 0.9906) (xy -0.2794 0.9906)
			)
			(stroke
				(width 0)
				(type default)
			)
			(fill no)
			(layer "F.CrtYd")
		)
		(fp_line
			(start 0.2794 -0.1016)
			(end -0.2794 -0.1016)
			(stroke
				(width 0.1)
				(type default)
			)
			(layer "F.Fab")
		)
		(fp_line
			(start -0.2794 -0.1016)
			(end -0.2794 0.9906)
			(stroke
				(width 0.1)
				(type default)
			)
			(layer "F.Fab")
		)
		(fp_line
			(start 0.2794 0.9906)
			(end 0.2794 -0.1016)
			(stroke
				(width 0.1)
				(type default)
			)
			(layer "F.Fab")
		)
		(fp_line
			(start -0.2794 0.9906)
			(end 0.2794 0.9906)
			(stroke
				(width 0.1)
				(type default)
			)
			(layer "F.Fab")
		)
		(pad "1" smd rect
			(at 0 0 90)
			(size 0.508 0.508)
			(layers "F.Cu" "F.Mask" "F.Paste")
			(net "P3V3_STBY")
		)
		(pad "2" smd rect
			(at 0 0.889 90)
			(size 0.508 0.508)
			(layers "F.Cu" "F.Mask" "F.Paste")
			(net "FM_CPLD_UART_CH_LOCK_N")
		)
		(zone
			(layer "F.Cu")
			(hatch none 0.5)
			(connect_pads
				(clearance 0)
			)
			(min_thickness 0.25)
			(keepout
				(tracks allowed)
				(vias not_allowed)
				(pads allowed)
				(copperpour not_allowed)
				(footprints allowed)
			)
			(placement
				(enabled no)
				(sheetname "")
			)
			(fill
				(thermal_gap 0.5)
				(thermal_bridge_width 0.5)
				(island_removal_mode 0)
			)
			(polygon
				(pts
					(xy 445.4525 -0.889) (xy 445.4525 -1.397) (xy 445.8335 -1.397) (xy 445.8335 -0.889)
				)
			)
		)
		(zone
			(layer "F.Cu")
			(hatch none 0.5)
			(connect_pads
				(clearance 0)
			)
			(min_thickness 0.25)
			(keepout
				(tracks not_allowed)
				(vias allowed)
				(pads allowed)
				(copperpour not_allowed)
				(footprints allowed)
			)
			(placement
				(enabled no)
				(sheetname "")
			)
			(fill
				(thermal_gap 0.5)
				(thermal_bridge_width 0.5)
				(island_removal_mode 0)
			)
			(polygon
				(pts
					(xy 445.8335 -0.889) (xy 445.8335 -1.397) (xy 445.4525 -1.397) (xy 445.4525 -0.889)
				)
			)
		)
	)
	(footprint ""
		(layer "F.Cu")
		(at 40.036496 -89.416382)
		(property "Reference" "L1C2"
			(at 3.378708 -4.251706 0)
			(unlocked yes)
			(layer "F.SilkS")
			(effects
				(font
					(size 0.4064 0.254)
					(thickness 0.1524)
				)
			)
		)
		(property "Value" ""
			(at 0 0 0)
			(layer "F.Fab")
			(effects
				(font
					(size 1.27 1.27)
				)
			)
		)
		(duplicate_pad_numbers_are_jumpers no)
		(fp_line
			(start -1.1303 -3.199892)
			(end 8.3693 -3.199892)
			(stroke
				(width 0.1524)
				(type default)
			)
			(layer "F.SilkS")
		)
		(fp_line
			(start -1.1303 -1.6637)
			(end -1.1303 -3.199892)
			(stroke
				(width 0.1524)
				(type default)
			)
			(layer "F.SilkS")
		)
		(fp_line
			(start -1.1303 3.199892)
			(end -1.1303 1.6637)
			(stroke
				(width 0.1524)
				(type default)
			)
			(layer "F.SilkS")
		)
		(fp_line
			(start 8.3693 -3.199892)
			(end 8.3693 -1.6637)
			(stroke
				(width 0.1524)
				(type default)
			)
			(layer "F.SilkS")
		)
		(fp_line
			(start 8.3693 1.6637)
			(end 8.3693 3.199892)
			(stroke
				(width 0.1524)
				(type default)
			)
			(layer "F.SilkS")
		)
		(fp_line
			(start 8.3693 3.199892)
			(end -1.1303 3.199892)
			(stroke
				(width 0.1524)
				(type default)
			)
			(layer "F.SilkS")
		)
		(fp_rect
			(start -1.1303 3.199892)
			(end 8.3693 -3.199892)
			(stroke
				(width 0)
				(type default)
			)
			(fill no)
			(layer "F.CrtYd")
		)
		(fp_line
			(start -1.1303 -3.199892)
			(end 8.3693 -3.199892)
			(stroke
				(width 0.1)
				(type default)
			)
			(layer "F.Fab")
		)
		(fp_line
			(start -1.1303 3.199892)
			(end -1.1303 -3.199892)
			(stroke
				(width 0.1)
				(type default)
			)
			(layer "F.Fab")
		)
		(fp_line
			(start 8.3693 -3.199892)
			(end 8.3693 3.199892)
			(stroke
				(width 0.1)
				(type default)
			)
			(layer "F.Fab")
		)
		(fp_line
			(start 8.3693 3.199892)
			(end -1.1303 3.199892)
			(stroke
				(width 0.1)
				(type default)
			)
			(layer "F.Fab")
		)
		(pad "1" smd rect
			(at 0 0)
			(size 3.683 2.667)
			(layers "F.Cu" "F.Mask" "F.Paste")
			(net "VR_PVCCIN_CPU1_PHASE5")
		)
		(pad "2" smd rect
			(at 7.239 0)
			(size 3.683 2.667)
			(layers "F.Cu" "F.Mask" "F.Paste")
			(net "PVCCIN_CPU1")
		)
	)
)
